FILE_TYPE = MACRO_DRAWING;
SET COLOR_WIRE YELLOW;
SET COLOR_PROP MONO;
SET COLOR_DOT WHITE;
SET COLOR_ARC YELLOW;
SET COLOR_BODY GREEN;
SET COLOR_NOTE MONO;
SET PROP_DISPLAY VALUE;
SET PAGE_NUMBER P265;
FORCEADD INTEL_CORP_BPAGE..1
(-1400 1675);
FORCEPROP 1 LAST CDS_CON_LAST_MODIFIED Fri Jun 16 17:49:40 2017
J 0
(-2825 2000);
PAINT ORANGE (-2825 2000);
DISPLAY INVISIBLE (-2825 2000);
FORCEPROP 1 LAST CUSTOM_TXT_CDS <CURRENT_DESIGN_SHEET> OF <TOTAL_DESIGN_SHEETS>
J 0
(-1900 1700);
PAINT ORANGE (-1900 1700);
FORCEPROP 2 LAST CUSTOM_TXT_CDS <XR_PAGE_TITLE>
J 0
(-9290 6925);
DISPLAY 0.638298 (-9290 6925);
PAINT PINK (-9290 6925);
DISPLAY INVISIBLE (-9290 6925);
FORCEPROP 2 LAST CUSTOM_TXT_CDS <CON_LAST_MODIFIED>
J 0
(-5400 1775);
PAINT ORANGE (-5400 1775);
FORCEPROP 1 LAST SCH_TITLE MCP JTAG BLOCK DIAGRAM
J 0
(-9350 1725);
DISPLAY 2.468085 (-9350 1725);
PAINT ORANGE (-9350 1725);
FORCEPROP 2 LAST CDS_LIB mstr_symbols
J 0
(-1400 1675);
PAINT MONO (-1400 1675);
DISPLAY INVISIBLE (-1400 1675);
FORCEPROP 2 LAST PAGE_BORDER TRUE
J 0
(-9290 6925);
DISPLAY 0.638298 (-9290 6925);
PAINT PINK (-9290 6925);
DISPLAY INVISIBLE (-9290 6925);
FORCEPROP 1 LAST COMMENT_BODY TRUE
J 0
(-1388 1687);
DISPLAY 0.468085 (-1388 1687);
PAINT GREEN (-1388 1687);
DISPLAY INVISIBLE (-1388 1687);
FORCEPROP 2 LAST CDS_XR_PAGE_TITLE CR-269 : @BASEBOARD_FAB2_LIB.BASEBOARD_FAB2(SCH_1):PAGE269
J 0
(-9290 6925);
DISPLAY 0.638298 (-9290 6925);
PAINT PINK (-9290 6925);
DISPLAY INVISIBLE (-9290 6925);
FORCENOTE
$CDS_IMAGE|CPU JTAG Block diagram_20160329.jpg|7332|5500
(-5400 4375) 0;
DISPLAY LEFT (-5400 4375);
QUIT
